# BASEBOARD_FAB2 (Tioga Pass) — schematic parts with pin connectivity, parts 4676–4676 of 4751; source: Cadence DE-HDL packaged netlist (pstxprt.dat, pstxnet.dat, pstchip.dat)

U7C1  LBG_CORE_QAT_EXT_D  IC  pkg BGA1  page 114  (pins 937-1248 of 1310)
  CA11  GPP_J17_LAN_SDP_P0_1  BI  = TP_PCH_GPP_J17
  CA13  GPP_J6_LAN_LED_P3_0  BI  = LED_GBE_P3_0
  CA15  VSS(4)  GROUND  = GND
  CA18  VSS(3)  GROUND  = GND
  CA20  GPP_I0_LAN_TDO  UNSPEC  = JTAG_PCH_GBE_TDO
  CA22  GPP_I2_LAN_TMS  UNSPEC  = JTAG_PCH_GBE_TMS
  CA24  GPP_I7_LAN_TRST_N  UNSPEC  = JTAG_PCH_GBE_TRST_N
  CA26  VSS(2)  GROUND  = GND
  CA28  GPP_C6_SML1CLK_IE  BI  = SMB_PMBUS_BMC_STBY_LVC3_SCL_R1
  CA30  GPP_C12  BI  = FM_BOARD_REV_ID0
  CA32  GPP_C15  BI  = FM_SLT_CFG0
  CA34  GPP_C22  BI  = IRQ_BMC_PCH_SMI_LPC_N
  CA37  GPP_C23  BI  = FM_CPU_CATERR_DLY_LVT3_R_N
  CA39  GPP_C20  BI  = FM_THROTTLE_R2_N
  CA41  GPP_D18  BI  = FM_XRC_READY_N
  CA43  GPP_D19  BI  = FM_ADR_MODE_SEL_R
  CA45  GPP_D7  BI  = FM_BMC_CPLD_GPO
  CA48  GPP_D20  BI  = FM_BMC_HEARTBEAT_N
  CA50  VSS(1)  GROUND  = GND
  CA52  VSS(0)  GROUND  = GND
  CA54  USB2N_11  BI  = TP_USB2_P11_DN
  CA57  USB2N_7  BI  = TP_USB2_P07_DN
  CA59  USB2N_3  BI  = TP_USB2_P03_DN
  CA61  USB2N_2  BI  = USB2_P02_DN_R
  CA63  USB2N_6  BI  = TP_USB2_P06_DN
  CA65  VSS(472)  GROUND  = GND
  CA66  VSS(473)  GROUND  = GND
  CA68  VSS(474)  GROUND  = GND
  CA70  VSS(453)  GROUND  = GND
  D8  RSVD(10)  UNSPEC  = FM_WBG_PRSNT_N
  D10  RSVD(20)  UNSPEC  = TP_PCH_RSVD20
  D12  VSS(431)  GROUND  = GND
  D14  GPD4_SLP_S3_N  BI  = FM_SLPS3_R_N
  D16  VSS(430)  GROUND  = GND
  D19  VSS(429)  GROUND  = GND
  D21  CLKOUT_SRCP(11)  BI  = CLK_100M_MEZZ4_DP
  D23  CLKOUT_SRCP(10)  BI  = CLK_100M_MEZZ3_DP
  D25  VSS(428)  GROUND  = GND
  D27  VSS(427)  GROUND  = GND
  D29  CLKOUT_PLAT0P  BI  = CLK_100M_BMC_PE_DP
  D31  CLKOUT_SRCN(8)  BI  = CLK_100M_MEZZ1_DN
  D33  CLKOUT_SRCN(6)  BI  = CLK_100M_PCH_SLOTX24_S4_DN
  D35  XTAL_OUT  BI  = XTAL_PCH_48M_OUT
  D38  CLKOUT_NSSCCAP1P  BI  = TP_CLK_100M_NSSCC1_DP
  D40  CLKOUT_PLAT1P  BI  = TP_CLK_100M_PLAT1_DP
  D42  DMI_RXN(0)  BI  = DMI_CPU0_PCH_TX_C_DN<0>
  D44  DMI_RXN(2)  BI  = DMI_CPU0_PCH_TX_C_DN<2>
  D47  VSS(424)  GROUND  = GND
  D49  PCIEUP_1_RXN  BI  = P3E_CPU0_PE1_PCH_TXN<1>
  D51  PCIEUP_3_RXN  BI  = P3E_CPU0_PE1_PCH_TXN<3>
  D53  PCIEUP_5_RXN  BI  = P3E_CPU0_PE1_PCH_TXN<5>
  D55  PCIEUP_7_RXN  BI  = P3E_CPU0_PE1_PCH_TXN<7>
  D58  PCIEUP_9_RXN  BI  = P3E_CPU0_PE1_PCH_C_TXP<9>
  D60  PCIEUP_11_RXN  BI  = P3E_CPU0_PE1_PCH_C_TXN<11>
  D62  PCIEUP_13_RXN  BI  = P3E_CPU0_PE1_PCH_C_TXP<13>
  D64  PCIEUP_15_RXN  BI  = P3E_CPU0_PE1_PCH_C_TXP<15>
  D66  EXTCLKN  BI  = A_EXTCLKN
  E1  VSS(461)  GROUND  = GND
  E3  VSS(485)  GROUND  = GND
  E6  VSS(402)  GROUND  = GND
  E9  VSS(398)  GROUND  = GND
  E11  VSS(423)  GROUND  = GND
  E13  VSS(422)  GROUND  = GND
  E15  VSS(421)  GROUND  = GND
  E18  RSVD(14)  UNSPEC  = TP_PCH_RSVD14
  E20  VSS(420)  GROUND  = GND
  E22  VSS(419)  GROUND  = GND
  E24  VSS(418)  GROUND  = GND
  E26  VSS(417)  GROUND  = GND
  E28  VSS(416)  GROUND  = GND
  E30  VSS(415)  GROUND  = GND
  E32  VSS(414)  GROUND  = GND
  E34  VSS(413)  GROUND  = GND
  E37  VSS(412)  GROUND  = GND
  E39  VSS(411)  GROUND  = GND
  E41  VSS(410)  GROUND  = GND
  E43  VSS(409)  GROUND  = GND
  E45  VSS(408)  GROUND  = GND
  E48  VSS(407)  GROUND  = GND
  E50  VSS(406)  GROUND  = GND
  E52  VSS(405)  GROUND  = GND
  E54  VSS(404)  GROUND  = GND
  E57  VSS(403)  GROUND  = GND
  E59  VSS(426)  GROUND  = GND
  E61  VSS(401)  GROUND  = GND
  E63  VSS(400)  GROUND  = GND
  E65  VSS(425)  GROUND  = GND
  E67  EXTCLKP  BI  = A_EXTCLKP
  E70  VSS(489)  GROUND  = GND
  E72  VSS(460)  GROUND  = GND
  F3  VSS(486)  GROUND  = GND
  F5  SPI0_IO2  BI  = SPI_PCH_IO2
  F8  RSVD(7)  UNSPEC  = TP_PCH_RSVD7
  F66  RSVD(9)  UNSPEC  = TP_PCH_RSVD9
  F69  RSVD(8)  UNSPEC  = TP_PCH_RSVD8
  F70  VSS(490)  GROUND  = GND
  G1  VSS(459)  GROUND  = GND
  G6  VSS(393)  GROUND  = GND
  G7  SPI0_FLASH_CS1_N  BI  = TP_SPI_PCH_CS1_R1_N
  G11  GPD6_SLP_A_N  BI  = FM_CPU0_SKTOCC_LVT3_N
  G15  GPD0  BI  = XDP_PCH_PWR_DEBUG_N
  G18  SRTCRST_N  BI  = RST_SRTCRST_N
  G22  VSS(397)  GROUND  = GND
  G26  CLKOUT_SRCP(9)  BI  = CLK_100M_MEZZ2_DP
  G29  VSS(396)  GROUND  = GND
  G33  CLKOUT_SRCP(2)  BI  = CLK_100M_PCH_SLOTX24_S0_DP
  G37  VSS(395)  GROUND  = GND
  G40  CLKOUT_SRCP(5)  BI  = CLK_100M_PCH_SLOTX24_S3_DP
  G44  XCLK_BIASREF  BI  = A_PCH_XCLK_BIASREF
  G48  VSS(394)  GROUND  = GND
  G52  PCIEUP_0_TXP  BI  = P3E_CPU0_PE1_PCH_RXP<0>
  G56  PCIEUP_2_TXP  BI  = P3E_CPU0_PE1_PCH_RXP<2>
  G59  VSS(399)  GROUND  = GND
  G63  VSS(392)  GROUND  = GND
  G66  VSS(391)  GROUND  = GND
  G67  RSVD(49)  UNSPEC  = TP_PCH_RSVD49
  G72  VSS(458)  GROUND  = GND
  H4  SPI0_MOSI_IO0  BI  = SPI_PCH_MOSI_R
  H9  GPD7  BI  = FM_BATTERY_SENSE_EN_R_N
  H13  GPD1_ACPRESENT  BI  = FM_CPU1_SKTOCC_LVT3_N
  H17  RTCX2  BI  = XTAL_33K_RTC2
  H20  HDA_SYNC  BI  = TP_PCH_HDA_SYNC
  H24  CLKOUT_SRCP(12)  BI  = NC
  H27  CLKOUT_SRCP(15)  BI  = CLK_100M_M2_DP
  H31  CLKOUT_SRCN(7)  BI  = CLK_100M_PCH_SLOTX24_S5_DN
  H35  CLKOUT_SRCP(1)  BI  = CLK_100M_DB1200_DP
  H38  CLKOUT_SRCP(0)  BI  = CLK_100M_AIRMAX8_PE1_DP
  H42  CLKOUT_SRCP(3)  BI  = CLK_100M_PCH_SLOTX24_S1_DP
  H46  DMI_TXN(0)  BI  = DMI_CPU0_PCH_RX_DN<0>
  H50  DMI_TXP(1)  BI  = DMI_CPU0_PCH_RX_DP<1>
  H54  PCIEUP_2_TXN  BI  = P3E_CPU0_PE1_PCH_RXN<2>
  H58  VSS(390)  GROUND  = GND
  H61  PCIEUP_6_TXN  BI  = P3E_CPU0_PE1_PCH_RXN<6>
  H65  VSS(386)  GROUND  = GND
  H69  RSVD(50)  UNSPEC  = TP_PCH_RSVD50
  J1  VSS(478)  GROUND  = GND
  J3  SPI0_FLASH_CS0_N  BI  = SPI_PCH_CS0_R_N
  J5  VSS(388)  GROUND  = GND
  J7  VSS(387)  GROUND  = GND
  J11  VSS(385)  GROUND  = GND
  J15  VSS(384)  GROUND  = GND
  J18  VSS(270)  GROUND  = GND
  J22  VSS(383)  GROUND  = GND
  J26  CLKOUT_SRCN(9)  BI  = CLK_100M_MEZZ2_DN
  J29  VSS(389)  GROUND  = GND
  J33  CLKOUT_SRCN(2)  BI  = CLK_100M_PCH_SLOTX24_S0_DN
  J37  VSS(382)  GROUND  = GND
  J40  CLKOUT_SRCN(5)  BI  = CLK_100M_PCH_SLOTX24_S3_DN
  J44  VSS(381)  GROUND  = GND
  J48  DMI_TXN(1)  BI  = DMI_CPU0_PCH_RX_DN<1>
  J52  PCIEUP_0_TXN  BI  = P3E_CPU0_PE1_PCH_RXN<0>
  J56  PCIEUP_3_TXN  BI  = P3E_CPU0_PE1_PCH_RXN<3>
  J59  VSS(380)  GROUND  = GND
  J63  PCIEUP_6_TXP  BI  = P3E_CPU0_PE1_PCH_RXP<6>
  J66  PCIEUP_9_TXN  BI  = P3E_CPU0_PE1_PCH_R_RXN<9>
  J68  VSS(379)  GROUND  = GND
  J70  VSS(378)  GROUND  = GND
  J72  VSS(477)  GROUND  = GND
  K2  SPI0_CLK  BI  = SPI_PCH_CLK
  K4  SPI0_TPM_CS_N  BI  = SPI_PCH_TPM_CS_N
  K9  WAKE_N  BI  = IRQ_LVC3_WAKE_N
  K13  DSW_PWROK  BI  = PWRGD_DSW_PWROK
  K17  RTCX1  BI  = XTAL_33K_RTC1
  K20  HDA_SDI_0  BI  = TP_PCH_HDA_SDI_0
  K24  CLKOUT_SRCN(12)  BI  = NC
  K27  CLKOUT_SRCN(15)  BI  = CLK_100M_M2_DN
  K31  CLKOUT_SRCP(7)  BI  = CLK_100M_PCH_SLOTX24_S5_DP
  K35  CLKOUT_SRCN(1)  BI  = CLK_100M_DB1200_DN
  K38  CLKOUT_SRCN(0)  BI  = CLK_100M_AIRMAX8_PE1_DN
  K42  CLKOUT_SRCN(3)  BI  = CLK_100M_PCH_SLOTX24_S1_DN
  K46  DMI_TXP(0)  BI  = DMI_CPU0_PCH_RX_DP<0>
  K50  DMI_TXN(2)  BI  = DMI_CPU0_PCH_RX_DN<2>
  K54  VSS(377)  GROUND  = GND
  K58  PCIEUP_3_TXP  BI  = P3E_CPU0_PE1_PCH_RXP<3>
  K61  PCIEUP_5_TXP  BI  = P3E_CPU0_PE1_PCH_RXP<5>
  K65  PCIEUP_8_TXN  BI  = P3E_CPU0_PE1_PCH_R_RXN<8>
  K69  VSS(376)  GROUND  = GND
  K71  VSS(375)  GROUND  = GND
  L1  SPI0_IO3  BI  = SPI_PCH_IO3
  L3  SPI0_MISO_IO1  BI  = SPI_PCH_MISO
  L5  VSS(374)  GROUND  = GND
  L68  VSS(373)  GROUND  = GND
  L70  PCIE19_UP7_SATA7_TXN  BI  = SATA6G_PCH_PCIE_UP_SATA_TXN<7>
  L72  PCIE19_UP7_SATA7_TXP  BI  = SATA6G_PCH_PCIE_UP_SATA_TXP<7>
  M2  VSS(372)  GROUND  = GND
  M4  VSS(366)  GROUND  = GND
  M7  TRIGGER_IN  BI  = TP_CPU_PCH_TRIGGER_IN
  M11  GPD2_GBE_WAKE_N  BI  = RST_BMC_SRST_R_N
  M15  SLP_GBE_N  BI  = TP_SLP_LAN_N
  M18  HDA_RST_N  BI  = TP_PCH_HSA_RST_N
  M22  VSS(371)  GROUND  = GND
  M26  VSS(370)  GROUND  = GND
  M29  VSS(369)  GROUND  = GND
  M33  VSS(368)  GROUND  = GND
  M37  VSS(367)  GROUND  = GND
  M40  VSS(365)  GROUND  = GND
  M44  VSS(362)  GROUND  = GND
  M48  VSS(361)  GROUND  = GND
  M52  DMI_TXP(2)  BI  = DMI_CPU0_PCH_RX_DP<2>
  M56  PCIEUP_1_TXP  BI  = P3E_CPU0_PE1_PCH_RXP<1>
  M59  PCIEUP_4_TXP  BI  = P3E_CPU0_PE1_PCH_RXP<4>
  M63  PCIEUP_8_TXP  BI  = P3E_CPU0_PE1_PCH_R_RXP<8>
  M66  PCIEUP_9_TXP  BI  = P3E_CPU0_PE1_PCH_R_RXP<9>
  M69  PCIE18_UP6_SATA6_TXN  BI  = SATA6G_PCH_PCIE_UP_SATA_TXN<6>
  M71  PCIE18_UP6_SATA6_TXP  BI  = SATA6G_PCH_PCIE_UP_SATA_TXP<6>
  N1  GPP_A2_LAD1_ESPI_IO1  BI  = LPC_LAD1_IO1
  N3  GPP_A0_RCIN_N_ESPI_ALERT1_N  BI  = PU_FM_RCIN_N
  N5  VSS(351)  GROUND  = GND
  N9  VSS(348)  GROUND  = GND
  N13  VSS(360)  GROUND  = GND
  N17  VSS(359)  GROUND  = GND
  N20  VSS(358)  GROUND  = GND
  N24  VSS(357)  GROUND  = GND
  N27  VSS(356)  GROUND  = GND
  N31  VSS(355)  GROUND  = GND
  N35  VSS(354)  GROUND  = GND
  N38  VSS(353)  GROUND  = GND
  N42  VSS(364)  GROUND  = GND
  N46  VSS(352)  GROUND  = GND
  N50  VSS(363)  GROUND  = GND
  N54  DMI_TXP(3)  BI  = DMI_CPU0_PCH_RX_DP<3>
  N58  PCIEUP_4_TXN  BI  = P3E_CPU0_PE1_PCH_RXN<4>
  N61  PCIEUP_5_TXN  BI  = P3E_CPU0_PE1_PCH_RXN<5>
  N65  PCIEUP_10_TXN  BI  = P3E_CPU0_PE1_PCH_R_RXN<10>
  N68  VSS(349)  GROUND  = GND
  N70  PCIE17_UP5_SATA5_TXN  BI  = SATA6G_PCH_PCIE_UP_SATA_TXN<5>
  N72  PCIE17_UP5_SATA5_TXP  BI  = SATA6G_PCH_PCIE_UP_SATA_TXP<5>
  P2  GPP_A6_SERIRQ_ESPI_CS1_N  BI  = IRQ_LPC_SERIRQ_N
  P4  GPP_A5_LFRAME_N_ESPI_CS0_N  BI  = LPC_LFRAME_N_CS0_N
  P7  SLP_SUS_N  BI  = FM_SLP_SUS_N
  P11  RTCRST_N  BI  = RST_RTCRST_N
  P15  RSMRST_N  BI  = RST_RSMRST_N
  P18  HDA_BCLK  BI  = TP_PCH_HDA_BCLK
  P22  RSVD(45)  UNSPEC  = TP_PCH_RSVD45
  P26  RSVD(53)  UNSPEC  = TP_PCH_RSVD53
  P29  RSVD(31)  UNSPEC  = TP_PCH_RSVD31
  P33  RSVD(29)  UNSPEC  = TP_PCH_RSVD29
  P37  RSVD(4)  UNSPEC  = TP_PCH_RSVD4
  P40  RSVD(23)  UNSPEC  = TP_PCH_RSVD23
  P44  RSVD(24)  UNSPEC  = TP_PCH_RSVD24
  P48  RSVD(25)  UNSPEC  = TP_PCH_RSVD25
  P52  DMI_TXN(3)  BI  = DMI_CPU0_PCH_RX_DN<3>
  P56  PCIEUP_1_TXN  BI  = P3E_CPU0_PE1_PCH_RXN<1>
  P59  PCIEUP_7_TXN  BI  = P3E_CPU0_PE1_PCH_RXN<7>
  P63  VSS(346)  GROUND  = GND
  P66  PCIEUP_10_TXP  BI  = P3E_CPU0_PE1_PCH_R_RXP<10>
  P69  PCIE16_UP4_SATA4_TXN  BI  = SATA6G_PCH_PCIE_UP_SATA_TXN<4>
  P71  PCIE16_UP4_SATA4_TXP  BI  = SATA6G_PCH_PCIE_UP_SATA_TXP<4>
  R1  GPP_A12_BMBUSY_N_SXEXITHLDOFF_N  BI  = PU_IRQ_PCH_SCI_WHEA_N
  R3  GPP_A9_CLKOUT_LPC0_ESPI_CLK  BI  = CLK_24M_BMC_LPC_R
  R5  VSS(343)  GROUND  = GND
  R9  PROC_PWRGD  BI  = PWRGD_CPUPWRGD_GTL
  R13  TRIGGER_OUT  BI  = TP_CPU_PCH_TRIGGER_OUT
  R17  PCH_PWROK  BI  = PWRGD_PCH_PWROK
  R20  RSVD(67)  BI  = TP_PCH_DISPA_SDI
  R24  RSVD(54)  UNSPEC  = TP_PCH_RSVD54
  R27  VSS(345)  GROUND  = GND
  R31  RSVD(30)  UNSPEC  = TP_PCH_RSVD30
  R35  RSVD(28)  UNSPEC  = TP_PCH_RSVD28
  R38  VSS(350)  GROUND  = GND
  R42  VCCPRIM_1P05(16)  POWER  = P1V05_PCH_STBY
  R46  VCCPRIM_1P05(15)  POWER  = P1V05_PCH_STBY
  R50  VSS(342)  GROUND  = GND
  R54  VSS(341)  GROUND  = GND
  R58  VSS(339)  GROUND  = GND
  R61  PCIEUP_7_TXP  BI  = P3E_CPU0_PE1_PCH_RXP<7>
  R65  PCIEUP_12_TXN  BI  = P3E_CPU0_PE1_PCH_R_RXN<12>
  R68  VSS(338)  GROUND  = GND
  R70  PCIE15_UP3_SATA3_TXN  BI  = SATA6G_PCH_PCIE_UP_SATA_TXN<3>
  R72  PCIE15_UP3_SATA3_TXP  BI  = SATA6G_PCH_PCIE_UP_SATA_TXP<3>
  T2  GPP_A16_CLKOUT_LPC2  BI  = FM_UART_PRES_N
  T4  GPP_A13_SUSWARN_N_SUSPWRDNACK  BI  = FM_MB_SLOT_ID0
  T7  VSS(324)  GROUND  = GND
  T11  VSS(337)  GROUND  = GND
  T15  VSS(336)  GROUND  = GND
  T18  VSS(335)  GROUND  = GND
  T22  VSS(334)  GROUND  = GND
  T26  VSS(333)  GROUND  = GND
  T29  VSS(332)  GROUND  = GND
  T33  VSS(331)  GROUND  = GND
  T37  VSS(330)  GROUND  = GND
  T40  VSS(329)  GROUND  = GND
  T44  VCCPRIM_1P05(14)  POWER  = P1V05_PCH_STBY
  T48  VSS(327)  GROUND  = GND
  T52  VSS(326)  GROUND  = GND
  T56  VSS(340)  GROUND  = GND
  T59  PCIEUP_11_TXN  BI  = P3E_CPU0_PE1_PCH_R_RXN<11>
  T63  PCIEUP_13_TXN  BI  = P3E_CPU0_PE1_PCH_R_RXN<13>
  T66  VSS(325)  GROUND  = GND
  T69  PCIE14_UP2_SATA2_TXN  BI  = SATA6G_PCH_PCIE_UP_SATA_TXN<2>
  T71  PCIE14_UP2_SATA2_TXP  BI  = SATA6G_PCH_PCIE_UP_SATA_TXP<2>
  U9  PECI  BI  = PECI_PCH
  U13  PM_SYNC  BI  = H_PM_SYNC1_GTL_R
  U17  PLTRST_CPU_N  BI  = TP_PLTRST_CPU_N
  U20  RSVD(66)  BI  = TP_PCH_DISPA_BCLK
  U24  HDA_SDO  BI  = FM_FLASH_DESC_OVERRIDE
  U27  VCCPRIM_AVID(31)  UNSPEC  = PVNN_PCH_STBY
  U31  VCCPRIM_AVID(61)  POWER  = PVNN_PCH_STBY
  U35  VCCPRIM_AVID(60)  POWER  = PVNN_PCH_STBY
  U38  VCCPRIM_AVID(59)  POWER  = PVNN_PCH_STBY
  U42  VSS(344)  GROUND  = GND
  U46  VCCPRIM_1P05(13)  POWER  = P1V05_PCH_STBY
  U50  VCCA_CLKUNF_1P05(1)  POWER  = P1V05_PCH_STBY
  U54  PREQ_N  BI  = XDP_PREQ_N
  U58  VSS(321)  GROUND  = GND
  U61  PCIEUP_13_TXP  BI  = P3E_CPU0_PE1_PCH_R_RXP<13>
  U65  PCIEUP_12_TXP  BI  = P3E_CPU0_PE1_PCH_R_RXP<12>
  V1  GPP_A23  BI  = FM_BMC_READY_R_N
  V3  GPP_A19  BI  = FM_ME_RECOVER_N
  V5  VSS(318)  GROUND  = GND
  V7  PM_SYNC2  BI  = TP_PM_SYNC_GTL
  V11  RSVD(3)  UNSPEC  = TP_PCH_RSVD3
